# T6G (Grand Teton) — schematic netlist excerpt (pin names and nets, part order shuffled) for the footprints in the layout excerpt that follows; sources: Cadence DE-HDL packaged netlist, KiCad conversion of 04192023_DAF0TMB3IC0_F0TG_MB_C_brd_V02_OCP.brd

R4265  Q_RES  4.7K 5% EMPTY  pkg 0402LF  page 241 : A = PWRGD_P3V3_AUX_PDB_BUF_R ; B = GND
PR411  Q_RES  0 5% CHIP  pkg 0402LF  page 208 : A = PVDD11_S3_P0_PVCC ; B = P5V_AUX
PC6902  Q_CAP  22UF 16V 20% X6S  pkg C0805  page 360 : A = SW_P12V_AUX_P1V8_RETIMER_CPU0_FLT ; B = GND

(kicad_pcb
	(version 20260206)
	(generator "pcbnew")
	(generator_version "10.0")
	(general
		(thickness 1.6)
		(legacy_teardrops no)
	)
	(paper "A4")
	(title_block
		(title "04192023_DAF0TMB3IC0_F0TG_MB_C_brd_V02_OCP.brd")
		(comment 1 "Grand Teton / footprints 3630-3632 of 8354")
	)
	(layers
		(0 "F.Cu" signal "TOP")
		(4 "In1.Cu" signal "GND")
		(6 "In2.Cu" signal "IN1")
		(8 "In3.Cu" signal "GND1")
		(10 "In4.Cu" signal "IN2")
		(12 "In5.Cu" signal "GND2")
		(14 "In6.Cu" signal "IN3")
		(16 "In7.Cu" signal "GND3")
		(18 "In8.Cu" signal "VCC")
		(20 "In9.Cu" signal "VCC1")
		(22 "In10.Cu" signal "GND4")
		(24 "In11.Cu" signal "IN4")
		(26 "In12.Cu" signal "GND5")
		(28 "In13.Cu" signal "IN5")
		(30 "In14.Cu" signal "GND6")
		(32 "In15.Cu" signal "IN6")
		(34 "In16.Cu" signal "GND7")
		(2 "B.Cu" signal "BOTTOM")
		(9 "F.Adhes" user "F.Adhesive")
		(11 "B.Adhes" user "B.Adhesive")
		(13 "F.Paste" user "Package Geometry/Pastemask Top")
		(15 "B.Paste" user "Package Geometry/Pastemask Bottom")
		(5 "F.SilkS" user "Ref Des/Silkscreen Top")
		(7 "B.SilkS" user "Ref Des/Silkscreen Bottom")
		(1 "F.Mask" user "Board Geometry/Soldermask Top")
		(3 "B.Mask" user "Board Geometry/Soldermask Bottom")
		(17 "Dwgs.User" user "User.Drawings")
		(19 "Cmts.User" user "User.Comments")
		(21 "Eco1.User" user "User.Eco1")
		(23 "Eco2.User" user "User.Eco2")
		(25 "Edge.Cuts" user "Board Geometry/Outline")
		(27 "Margin" user)
		(31 "F.CrtYd" user "Package Geometry/Place Bound Top")
		(29 "B.CrtYd" user "Package Geometry/Place Bound Bottom")
		(35 "F.Fab" user "Ref Des/Assembly Top")
		(33 "B.Fab" user "Ref Des/Assembly Bottom")
	)
	(footprint ""
		(layer "F.Cu")
		(at 277.650956 -429.572166 180)
		(property "Reference" "R4265"
			(at 0 0 180)
			(layer "F.SilkS")
			(hide yes)
			(effects
				(font
					(size 1.27 1.27)
				)
			)
		)
		(property "Value" ""
			(at 0 0 180)
			(layer "F.Fab")
			(effects
				(font
					(size 1.27 1.27)
				)
			)
		)
		(duplicate_pad_numbers_are_jumpers no)
		(fp_line
			(start 0.7874 0.4064)
			(end -0.7874 0.4064)
			(stroke
				(width 0.1524)
				(type default)
			)
			(layer "F.SilkS")
		)
		(fp_line
			(start 0.7874 -0.4064)
			(end 0.7874 0.4064)
			(stroke
				(width 0.1524)
				(type default)
			)
			(layer "F.SilkS")
		)
		(fp_line
			(start -0.7874 0.4064)
			(end -0.7874 -0.4064)
			(stroke
				(width 0.1524)
				(type default)
			)
			(layer "F.SilkS")
		)
		(fp_line
			(start -0.7874 -0.4064)
			(end 0.7874 -0.4064)
			(stroke
				(width 0.1524)
				(type default)
			)
			(layer "F.SilkS")
		)
		(fp_line
			(start 0.67945 0.3048)
			(end 0.120396 0.3048)
			(stroke
				(width 0.1)
				(type default)
			)
			(layer "F.Fab")
		)
		(fp_line
			(start 0.67945 -0.3048)
			(end 0.67945 0.3048)
			(stroke
				(width 0.1)
				(type default)
			)
			(layer "F.Fab")
		)
		(fp_line
			(start 0.12065 -0.2794)
			(end 0.12065 -0.3048)
			(stroke
				(width 0.1)
				(type default)
			)
			(layer "F.Fab")
		)
		(fp_line
			(start 0.12065 -0.3048)
			(end 0.67945 -0.3048)
			(stroke
				(width 0.1)
				(type default)
			)
			(layer "F.Fab")
		)
		(fp_line
			(start 0.120396 0.3048)
			(end 0.120396 0.2794)
			(stroke
				(width 0.1)
				(type default)
			)
			(layer "F.Fab")
		)
		(fp_line
			(start 0.120396 0.2794)
			(end -0.12065 0.2794)
			(stroke
				(width 0.1)
				(type default)
			)
			(layer "F.Fab")
		)
		(fp_line
			(start -0.12065 0.3048)
			(end -0.67945 0.3048)
			(stroke
				(width 0.1)
				(type default)
			)
			(layer "F.Fab")
		)
		(fp_line
			(start -0.12065 0.2794)
			(end -0.12065 0.3048)
			(stroke
				(width 0.1)
				(type default)
			)
			(layer "F.Fab")
		)
		(fp_line
			(start -0.12065 -0.2794)
			(end 0.12065 -0.2794)
			(stroke
				(width 0.1)
				(type default)
			)
			(layer "F.Fab")
		)
		(fp_line
			(start -0.12065 -0.305054)
			(end -0.12065 -0.2794)
			(stroke
				(width 0.1)
				(type default)
			)
			(layer "F.Fab")
		)
		(fp_line
			(start -0.67945 0.3048)
			(end -0.67945 -0.305054)
			(stroke
				(width 0.1)
				(type default)
			)
			(layer "F.Fab")
		)
		(fp_line
			(start -0.67945 -0.305054)
			(end -0.12065 -0.305054)
			(stroke
				(width 0.1)
				(type default)
			)
			(layer "F.Fab")
		)
		(pad "1" smd circle
			(at -0.40005 0 180)
			(size 0 0)
			(layers "F.Cu" "F.Mask" "F.Paste")
			(net "PWRGD_P3V3_AUX_PDB_BUF_R")
		)
		(pad "2" smd circle
			(at 0.40005 0 180)
			(size 0 0)
			(layers "F.Cu" "F.Mask" "F.Paste")
			(net "GND")
		)
	)
	(footprint ""
		(layer "F.Cu")
		(at 418.896038 -353.763072 90)
		(property "Reference" "PR411"
			(at 0 0 90)
			(layer "F.SilkS")
			(hide yes)
			(effects
				(font
					(size 1.27 1.27)
				)
			)
		)
		(property "Value" ""
			(at 0 0 90)
			(layer "F.Fab")
			(effects
				(font
					(size 1.27 1.27)
				)
			)
		)
		(duplicate_pad_numbers_are_jumpers no)
		(fp_line
			(start 0.7874 -0.4064)
			(end 0.7874 0.4064)
			(stroke
				(width 0.1524)
				(type default)
			)
			(layer "F.SilkS")
		)
		(fp_line
			(start -0.7874 -0.4064)
			(end 0.7874 -0.4064)
			(stroke
				(width 0.1524)
				(type default)
			)
			(layer "F.SilkS")
		)
		(fp_line
			(start 0.7874 0.4064)
			(end -0.7874 0.4064)
			(stroke
				(width 0.1524)
				(type default)
			)
			(layer "F.SilkS")
		)
		(fp_line
			(start -0.7874 0.4064)
			(end -0.7874 -0.4064)
			(stroke
				(width 0.1524)
				(type default)
			)
			(layer "F.SilkS")
		)
		(fp_line
			(start -0.12065 -0.305054)
			(end -0.12065 -0.2794)
			(stroke
				(width 0.1)
				(type default)
			)
			(layer "F.Fab")
		)
		(fp_line
			(start -0.67945 -0.305054)
			(end -0.12065 -0.305054)
			(stroke
				(width 0.1)
				(type default)
			)
			(layer "F.Fab")
		)
		(fp_line
			(start 0.67945 -0.3048)
			(end 0.67945 0.3048)
			(stroke
				(width 0.1)
				(type default)
			)
			(layer "F.Fab")
		)
		(fp_line
			(start 0.12065 -0.3048)
			(end 0.67945 -0.3048)
			(stroke
				(width 0.1)
				(type default)
			)
			(layer "F.Fab")
		)
		(fp_line
			(start 0.12065 -0.2794)
			(end 0.12065 -0.3048)
			(stroke
				(width 0.1)
				(type default)
			)
			(layer "F.Fab")
		)
		(fp_line
			(start -0.12065 -0.2794)
			(end 0.12065 -0.2794)
			(stroke
				(width 0.1)
				(type default)
			)
			(layer "F.Fab")
		)
		(fp_line
			(start 0.120396 0.2794)
			(end -0.12065 0.2794)
			(stroke
				(width 0.1)
				(type default)
			)
			(layer "F.Fab")
		)
		(fp_line
			(start -0.12065 0.2794)
			(end -0.12065 0.3048)
			(stroke
				(width 0.1)
				(type default)
			)
			(layer "F.Fab")
		)
		(fp_line
			(start 0.67945 0.3048)
			(end 0.120396 0.3048)
			(stroke
				(width 0.1)
				(type default)
			)
			(layer "F.Fab")
		)
		(fp_line
			(start 0.120396 0.3048)
			(end 0.120396 0.2794)
			(stroke
				(width 0.1)
				(type default)
			)
			(layer "F.Fab")
		)
		(fp_line
			(start -0.12065 0.3048)
			(end -0.67945 0.3048)
			(stroke
				(width 0.1)
				(type default)
			)
			(layer "F.Fab")
		)
		(fp_line
			(start -0.67945 0.3048)
			(end -0.67945 -0.305054)
			(stroke
				(width 0.1)
				(type default)
			)
			(layer "F.Fab")
		)
		(pad "1" smd circle
			(at -0.40005 0 90)
			(size 0 0)
			(layers "F.Cu" "F.Mask" "F.Paste")
			(net "PVDD11_S3_P0_PVCC")
		)
		(pad "2" smd circle
			(at 0.40005 0 90)
			(size 0 0)
			(layers "F.Cu" "F.Mask" "F.Paste")
			(net "P5V_AUX")
		)
	)
	(footprint ""
		(layer "F.Cu")
		(at 240.792 -287.0708 180)
		(property "Reference" "PC6902"
			(at 0 0 180)
			(layer "F.SilkS")
			(hide yes)
			(effects
				(font
					(size 1.27 1.27)
				)
			)
		)
		(property "Value" ""
			(at 0 0 180)
			(layer "F.Fab")
			(effects
				(font
					(size 1.27 1.27)
				)
			)
		)
		(duplicate_pad_numbers_are_jumpers no)
		(fp_line
			(start 1.524 0.762)
			(end -1.524 0.762)
			(stroke
				(width 0.1524)
				(type default)
			)
			(layer "F.SilkS")
		)
		(fp_line
			(start 1.524 -0.762)
			(end 1.524 0.762)
			(stroke
				(width 0.1524)
				(type default)
			)
			(layer "F.SilkS")
		)
		(fp_line
			(start -1.524 0.762)
			(end -1.524 -0.762)
			(stroke
				(width 0.1524)
				(type default)
			)
			(layer "F.SilkS")
		)
		(fp_line
			(start -1.524 -0.762)
			(end 1.524 -0.762)
			(stroke
				(width 0.1524)
				(type default)
			)
			(layer "F.SilkS")
		)
		(fp_line
			(start 1.1049 0.724916)
			(end 1.1049 -0.724916)
			(stroke
				(width 0.1)
				(type default)
			)
			(layer "F.Fab")
		)
		(fp_line
			(start 1.1049 -0.724916)
			(end -1.1049 -0.724916)
			(stroke
				(width 0.1)
				(type default)
			)
			(layer "F.Fab")
		)
		(fp_line
			(start -1.1049 0.724916)
			(end 1.1049 0.724916)
			(stroke
				(width 0.1)
				(type default)
			)
			(layer "F.Fab")
		)
		(fp_line
			(start -1.1049 -0.724916)
			(end -1.1049 0.724916)
			(stroke
				(width 0.1)
				(type default)
			)
			(layer "F.Fab")
		)
		(pad "1" smd rect
			(at -0.889 0)
			(size 1.016 1.27)
			(layers "F.Cu" "F.Mask" "F.Paste")
			(net "SW_P12V_AUX_P1V8_RETIMER_CPU0_FLT")
		)
		(pad "2" smd rect
			(at 0.889 0)
			(size 1.016 1.27)
			(layers "F.Cu" "F.Mask" "F.Paste")
			(net "GND")
		)
	)
)
